(kicad_pcb
	(version 20260206)
	(generator "pcbnew")
	(generator_version "10.0")
	(general
		(thickness 1.6)
		(legacy_teardrops no)
	)
	(paper "A4")
	(title_block
		(title "v1-chassis-manager — T6M_CM_d_v01_1031_1645.brd")
		(comment 1 "Open CloudServer (Microsoft) / footprints 2274-2283 of 2512")
	)
	(layers
		(0 "F.Cu" signal "TOP")
		(4 "In1.Cu" signal "GND1")
		(6 "In2.Cu" signal "IN1")
		(8 "In3.Cu" signal "VCC1")
		(10 "In4.Cu" signal "VCC2")
		(12 "In5.Cu" signal "GND2")
		(14 "In6.Cu" signal "IN2")
		(16 "In7.Cu" signal "IN3")
		(18 "In8.Cu" signal "GND3")
		(2 "B.Cu" signal "BOTTOM")
		(9 "F.Adhes" user "F.Adhesive")
		(11 "B.Adhes" user "B.Adhesive")
		(13 "F.Paste" user "Package Geometry/Pastemask Top")
		(15 "B.Paste" user "Package Geometry/Pastemask Bottom")
		(5 "F.SilkS" user "Ref Des/Silkscreen Top")
		(7 "B.SilkS" user "Ref Des/Silkscreen Bottom")
		(1 "F.Mask" user "Board Geometry/Soldermask Top")
		(3 "B.Mask" user "Board Geometry/Soldermask Bottom")
		(17 "Dwgs.User" user "User.Drawings")
		(19 "Cmts.User" user "User.Comments")
		(21 "Eco1.User" user "User.Eco1")
		(23 "Eco2.User" user "User.Eco2")
		(25 "Edge.Cuts" user "Board Geometry/Outline")
		(27 "Margin" user)
		(31 "F.CrtYd" user "Package Geometry/Place Bound Top")
		(29 "B.CrtYd" user "Package Geometry/Place Bound Bottom")
		(35 "F.Fab" user "Ref Des/Assembly Top")
		(33 "B.Fab" user "Ref Des/Assembly Bottom")
	)
	(footprint ""
		(layer "B.Cu")
		(at 130.56616 -30.610048 180)
		(property "Reference" "R776"
			(at -3.80746 -0.509016 0)
			(unlocked yes)
			(layer "B.SilkS")
			(effects
				(font
					(size 0.7874 0.5842)
					(thickness 0.1524)
				)
				(justify left mirror)
			)
		)
		(property "Value" ""
			(at 0 0 0)
			(layer "B.Fab")
			(effects
				(font
					(size 1.27 1.27)
				)
				(justify mirror)
			)
		)
		(duplicate_pad_numbers_are_jumpers no)
		(fp_line
			(start 0.7874 0.4064)
			(end 0.7874 -0.4064)
			(stroke
				(width 0.1524)
				(type default)
			)
			(layer "B.SilkS")
		)
		(fp_line
			(start 0.7874 -0.4064)
			(end -0.7874 -0.4064)
			(stroke
				(width 0.1524)
				(type default)
			)
			(layer "B.SilkS")
		)
		(fp_line
			(start -0.7874 0.4064)
			(end 0.7874 0.4064)
			(stroke
				(width 0.1524)
				(type default)
			)
			(layer "B.SilkS")
		)
		(fp_line
			(start -0.7874 -0.4064)
			(end -0.7874 0.4064)
			(stroke
				(width 0.1524)
				(type default)
			)
			(layer "B.SilkS")
		)
		(fp_poly
			(pts
				(xy 0.508 0.2794) (xy 0.508 0.2286) (xy 0.635 0.2286) (xy 0.635 -0.254) (xy 0.5334 -0.254) (xy 0.5334 -0.2794)
				(xy -0.5334 -0.2794) (xy -0.5334 -0.254) (xy -0.635 -0.254) (xy -0.635 0.254) (xy -0.5334 0.254)
				(xy -0.5334 0.2794)
			)
			(stroke
				(width 0)
				(type default)
			)
			(fill no)
			(layer "B.CrtYd")
		)
		(pad "1" smd rect
			(at -0.40005 0)
			(size 0.4572 0.508)
			(layers "B.Cu" "B.Mask" "B.Paste")
			(net "P3V3_NODE1")
		)
		(pad "2" smd rect
			(at 0.40005 0)
			(size 0.4572 0.508)
			(layers "B.Cu" "B.Mask" "B.Paste")
			(net "UART_RI_P6_N")
		)
	)
	(footprint ""
		(layer "B.Cu")
		(at 37.645086 -138.392662)
		(property "Reference" "R262"
			(at -2.11328 -0.033782 0)
			(unlocked yes)
			(layer "B.SilkS")
			(effects
				(font
					(size 0.7874 0.5842)
					(thickness 0.1524)
				)
				(justify left mirror)
			)
		)
		(property "Value" ""
			(at 0 0 0)
			(layer "B.Fab")
			(effects
				(font
					(size 1.27 1.27)
				)
				(justify mirror)
			)
		)
		(duplicate_pad_numbers_are_jumpers no)
		(fp_line
			(start -0.7874 -0.4064)
			(end -0.7874 0.4064)
			(stroke
				(width 0.1524)
				(type default)
			)
			(layer "B.SilkS")
		)
		(fp_line
			(start -0.7874 0.4064)
			(end 0.7874 0.4064)
			(stroke
				(width 0.1524)
				(type default)
			)
			(layer "B.SilkS")
		)
		(fp_line
			(start 0.7874 -0.4064)
			(end -0.7874 -0.4064)
			(stroke
				(width 0.1524)
				(type default)
			)
			(layer "B.SilkS")
		)
		(fp_line
			(start 0.7874 0.4064)
			(end 0.7874 -0.4064)
			(stroke
				(width 0.1524)
				(type default)
			)
			(layer "B.SilkS")
		)
		(fp_poly
			(pts
				(xy 0.508 0.2794) (xy 0.508 0.2286) (xy 0.635 0.2286) (xy 0.635 -0.254) (xy 0.5334 -0.254) (xy 0.5334 -0.2794)
				(xy -0.5334 -0.2794) (xy -0.5334 -0.254) (xy -0.635 -0.254) (xy -0.635 0.254) (xy -0.5334 0.254)
				(xy -0.5334 0.2794)
			)
			(stroke
				(width 0)
				(type default)
			)
			(fill no)
			(layer "B.CrtYd")
		)
		(pad "1" smd rect
			(at -0.40005 0 180)
			(size 0.4572 0.508)
			(layers "B.Cu" "B.Mask" "B.Paste")
			(net "P0V75_BMC_VTTREF_NODE1")
		)
		(pad "2" smd rect
			(at 0.40005 0 180)
			(size 0.4572 0.508)
			(layers "B.Cu" "B.Mask" "B.Paste")
			(net "GND")
		)
	)
	(footprint ""
		(layer "B.Cu")
		(at 40.185086 -143.472662 180)
		(property "Reference" "C229"
			(at 3.121914 0.085598 0)
			(unlocked yes)
			(layer "B.SilkS")
			(effects
				(font
					(size 0.7874 0.5842)
					(thickness 0.1524)
				)
				(justify mirror)
			)
		)
		(property "Value" ""
			(at 0 0 0)
			(layer "B.Fab")
			(effects
				(font
					(size 1.27 1.27)
				)
				(justify mirror)
			)
		)
		(duplicate_pad_numbers_are_jumpers no)
		(fp_line
			(start 1.2954 0.5842)
			(end 1.2954 -0.5842)
			(stroke
				(width 0.1524)
				(type default)
			)
			(layer "B.SilkS")
		)
		(fp_line
			(start 1.2954 -0.5842)
			(end -1.2954 -0.5842)
			(stroke
				(width 0.1524)
				(type default)
			)
			(layer "B.SilkS")
		)
		(fp_line
			(start 0 -0.5842)
			(end 0 0.5842)
			(stroke
				(width 0.1524)
				(type default)
			)
			(layer "B.SilkS")
		)
		(fp_line
			(start -1.2954 0.5842)
			(end 1.2954 0.5842)
			(stroke
				(width 0.1524)
				(type default)
			)
			(layer "B.SilkS")
		)
		(fp_line
			(start -1.2954 -0.5842)
			(end -1.2954 0.5842)
			(stroke
				(width 0.1524)
				(type default)
			)
			(layer "B.SilkS")
		)
		(fp_poly
			(pts
				(xy -0.8636 -0.4572) (xy -0.8636 -0.3556) (xy -1.143 -0.3556) (xy -1.143 0.3556) (xy -0.8636 0.3556)
				(xy -0.8636 0.4572) (xy 0.8636 0.4572) (xy 0.8636 0.3556) (xy 1.143 0.3556) (xy 1.143 -0.3556) (xy 0.8636 -0.3556)
				(xy 0.8636 -0.4572)
			)
			(stroke
				(width 0)
				(type default)
			)
			(fill no)
			(layer "B.CrtYd")
		)
		(fp_line
			(start 0.884936 0.504952)
			(end 0.884936 -0.504952)
			(stroke
				(width 0.1)
				(type default)
			)
			(layer "B.Fab")
		)
		(fp_line
			(start 0.884936 -0.504952)
			(end -0.884936 -0.504952)
			(stroke
				(width 0.1)
				(type default)
			)
			(layer "B.Fab")
		)
		(fp_line
			(start -0.884936 0.504952)
			(end 0.884936 0.504952)
			(stroke
				(width 0.1)
				(type default)
			)
			(layer "B.Fab")
		)
		(fp_line
			(start -0.884936 -0.504952)
			(end -0.884936 0.504952)
			(stroke
				(width 0.1)
				(type default)
			)
			(layer "B.Fab")
		)
		(pad "1" smd rect
			(at -0.7366 0 270)
			(size 0.7112 0.8128)
			(layers "B.Cu" "B.Mask" "B.Paste")
			(net "P1V538_BMC_NODE1")
		)
		(pad "2" smd rect
			(at 0.7366 0 270)
			(size 0.7112 0.8128)
			(layers "B.Cu" "B.Mask" "B.Paste")
			(net "GND")
		)
	)
	(footprint ""
		(layer "B.Cu")
		(at 75.415902 -129.389124 90)
		(property "Reference" "R256"
			(at 1.673098 -0.09398 270)
			(unlocked yes)
			(layer "B.SilkS")
			(effects
				(font
					(size 0.7874 0.5842)
					(thickness 0.1524)
				)
				(justify left mirror)
			)
		)
		(property "Value" ""
			(at 0 0 90)
			(layer "B.Fab")
			(effects
				(font
					(size 1.27 1.27)
				)
				(justify mirror)
			)
		)
		(duplicate_pad_numbers_are_jumpers no)
		(fp_line
			(start 0.7874 -0.4064)
			(end -0.7874 -0.4064)
			(stroke
				(width 0.1524)
				(type default)
			)
			(layer "B.SilkS")
		)
		(fp_line
			(start -0.7874 -0.4064)
			(end -0.7874 0.4064)
			(stroke
				(width 0.1524)
				(type default)
			)
			(layer "B.SilkS")
		)
		(fp_line
			(start 0.7874 0.4064)
			(end 0.7874 -0.4064)
			(stroke
				(width 0.1524)
				(type default)
			)
			(layer "B.SilkS")
		)
		(fp_line
			(start -0.7874 0.4064)
			(end 0.7874 0.4064)
			(stroke
				(width 0.1524)
				(type default)
			)
			(layer "B.SilkS")
		)
		(fp_poly
			(pts
				(xy 0.508 0.2794) (xy 0.508 0.2286) (xy 0.635 0.2286) (xy 0.635 -0.254) (xy 0.5334 -0.254) (xy 0.5334 -0.2794)
				(xy -0.5334 -0.2794) (xy -0.5334 -0.254) (xy -0.635 -0.254) (xy -0.635 0.254) (xy -0.5334 0.254)
				(xy -0.5334 0.2794)
			)
			(stroke
				(width 0)
				(type default)
			)
			(fill no)
			(layer "B.CrtYd")
		)
		(pad "1" smd rect
			(at -0.40005 0 270)
			(size 0.4572 0.508)
			(layers "B.Cu" "B.Mask" "B.Paste")
			(net "PD_BMC_NODE1_PEREXT")
		)
		(pad "2" smd rect
			(at 0.40005 0 270)
			(size 0.4572 0.508)
			(layers "B.Cu" "B.Mask" "B.Paste")
			(net "GND")
		)
	)
	(footprint ""
		(layer "B.Cu")
		(at 135.162036 -42.501566 180)
		(property "Reference" "R1119"
			(at 5.38099 -18.982944 0)
			(unlocked yes)
			(layer "B.SilkS")
			(effects
				(font
					(size 0.7874 0.5842)
					(thickness 0.1524)
				)
				(justify left mirror)
			)
		)
		(property "Value" ""
			(at 0 0 0)
			(layer "B.Fab")
			(effects
				(font
					(size 1.27 1.27)
				)
				(justify mirror)
			)
		)
		(duplicate_pad_numbers_are_jumpers no)
		(fp_line
			(start 0.7874 0.4064)
			(end 0.7874 -0.4064)
			(stroke
				(width 0.1524)
				(type default)
			)
			(layer "B.SilkS")
		)
		(fp_line
			(start 0.7874 -0.4064)
			(end -0.7874 -0.4064)
			(stroke
				(width 0.1524)
				(type default)
			)
			(layer "B.SilkS")
		)
		(fp_line
			(start -0.7874 0.4064)
			(end 0.7874 0.4064)
			(stroke
				(width 0.1524)
				(type default)
			)
			(layer "B.SilkS")
		)
		(fp_line
			(start -0.7874 -0.4064)
			(end -0.7874 0.4064)
			(stroke
				(width 0.1524)
				(type default)
			)
			(layer "B.SilkS")
		)
		(fp_poly
			(pts
				(xy 0.508 0.2794) (xy 0.508 0.2286) (xy 0.635 0.2286) (xy 0.635 -0.254) (xy 0.5334 -0.254) (xy 0.5334 -0.2794)
				(xy -0.5334 -0.2794) (xy -0.5334 -0.254) (xy -0.635 -0.254) (xy -0.635 0.254) (xy -0.5334 0.254)
				(xy -0.5334 0.2794)
			)
			(stroke
				(width 0)
				(type default)
			)
			(fill no)
			(layer "B.CrtYd")
		)
		(pad "1" smd rect
			(at -0.40005 0)
			(size 0.4572 0.508)
			(layers "B.Cu" "B.Mask" "B.Paste")
			(net "SIO_JTAG_CPLD2_TCK")
		)
		(pad "2" smd rect
			(at 0.40005 0)
			(size 0.4572 0.508)
			(layers "B.Cu" "B.Mask" "B.Paste")
			(net "JTAG_CPLD2_TCK")
		)
	)
	(footprint ""
		(layer "B.Cu")
		(at 166.151814 -145.208498 -90)
		(property "Reference" "TP4"
			(at 0 0 90)
			(layer "B.SilkS")
			(hide yes)
			(effects
				(font
					(size 1.27 1.27)
				)
				(justify mirror)
			)
		)
		(property "Value" ""
			(at 0 0 90)
			(layer "B.Fab")
			(effects
				(font
					(size 1.27 1.27)
				)
				(justify mirror)
			)
		)
		(duplicate_pad_numbers_are_jumpers no)
		(fp_poly
			(pts
				(arc
					(start 0 -0.381)
					(mid 0 0.381)
					(end 0 -0.381)
				)
			)
			(stroke
				(width 0)
				(type default)
			)
			(fill no)
			(layer "B.CrtYd")
		)
		(pad "1" smd circle
			(at 0 0 90)
			(size 0.762 0.762)
			(layers "B.Cu" "B.Mask" "B.Paste")
			(net "N21357373")
		)
	)
	(footprint ""
		(layer "B.Cu")
		(at 154.06116 -171.489624)
		(property "Reference" "R750"
			(at -1.545844 12.970002 0)
			(unlocked yes)
			(layer "B.SilkS")
			(effects
				(font
					(size 0.7874 0.5842)
					(thickness 0.1524)
				)
				(justify left mirror)
			)
		)
		(property "Value" ""
			(at 0 0 0)
			(layer "B.Fab")
			(effects
				(font
					(size 1.27 1.27)
				)
				(justify mirror)
			)
		)
		(duplicate_pad_numbers_are_jumpers no)
		(fp_line
			(start -0.7874 -0.4064)
			(end -0.7874 0.4064)
			(stroke
				(width 0.1524)
				(type default)
			)
			(layer "B.SilkS")
		)
		(fp_line
			(start -0.7874 0.4064)
			(end 0.7874 0.4064)
			(stroke
				(width 0.1524)
				(type default)
			)
			(layer "B.SilkS")
		)
		(fp_line
			(start 0.7874 -0.4064)
			(end -0.7874 -0.4064)
			(stroke
				(width 0.1524)
				(type default)
			)
			(layer "B.SilkS")
		)
		(fp_line
			(start 0.7874 0.4064)
			(end 0.7874 -0.4064)
			(stroke
				(width 0.1524)
				(type default)
			)
			(layer "B.SilkS")
		)
		(fp_poly
			(pts
				(xy 0.508 0.2794) (xy 0.508 0.2286) (xy 0.635 0.2286) (xy 0.635 -0.254) (xy 0.5334 -0.254) (xy 0.5334 -0.2794)
				(xy -0.5334 -0.2794) (xy -0.5334 -0.254) (xy -0.635 -0.254) (xy -0.635 0.254) (xy -0.5334 0.254)
				(xy -0.5334 0.2794)
			)
			(stroke
				(width 0)
				(type default)
			)
			(fill no)
			(layer "B.CrtYd")
		)
		(pad "1" smd rect
			(at -0.40005 0 180)
			(size 0.4572 0.508)
			(layers "B.Cu" "B.Mask" "B.Paste")
			(net "N21698959")
		)
		(pad "2" smd rect
			(at 0.40005 0 180)
			(size 0.4572 0.508)
			(layers "B.Cu" "B.Mask" "B.Paste")
			(net "GND")
		)
	)
	(footprint ""
		(layer "B.Cu")
		(at 72.191372 -80.514698 90)
		(property "Reference" "C73"
			(at -32.158686 -14.55039 270)
			(unlocked yes)
			(layer "B.SilkS")
			(effects
				(font
					(size 0.7874 0.5842)
					(thickness 0.1524)
				)
				(justify left mirror)
			)
		)
		(property "Value" ""
			(at 0 0 90)
			(layer "B.Fab")
			(effects
				(font
					(size 1.27 1.27)
				)
				(justify mirror)
			)
		)
		(duplicate_pad_numbers_are_jumpers no)
		(fp_line
			(start 0.7874 -0.4064)
			(end -0.7874 -0.4064)
			(stroke
				(width 0.1524)
				(type default)
			)
			(layer "B.SilkS")
		)
		(fp_line
			(start -0.7874 -0.4064)
			(end -0.7874 0.4064)
			(stroke
				(width 0.1524)
				(type default)
			)
			(layer "B.SilkS")
		)
		(fp_line
			(start 0 0.381)
			(end 0 -0.381)
			(stroke
				(width 0.1524)
				(type default)
			)
			(layer "B.SilkS")
		)
		(fp_line
			(start 0.7874 0.4064)
			(end 0.7874 -0.4064)
			(stroke
				(width 0.1524)
				(type default)
			)
			(layer "B.SilkS")
		)
		(fp_line
			(start -0.7874 0.4064)
			(end 0.7874 0.4064)
			(stroke
				(width 0.1524)
				(type default)
			)
			(layer "B.SilkS")
		)
		(fp_poly
			(pts
				(xy 0.5334 0.254) (xy 0.635 0.254) (xy 0.635 0.2286) (xy 0.635 -0.254) (xy 0.5334 -0.254) (xy 0.5334 -0.2794)
				(xy -0.5334 -0.2794) (xy -0.5334 -0.254) (xy -0.635 -0.254) (xy -0.635 0.254) (xy -0.5334 0.254)
				(xy -0.5334 0.2794) (xy 0.508 0.2794) (xy 0.5334 0.2794)
			)
			(stroke
				(width 0)
				(type default)
			)
			(fill no)
			(layer "B.CrtYd")
		)
		(pad "1" smd rect
			(at -0.40005 0 270)
			(size 0.4572 0.508)
			(layers "B.Cu" "B.Mask" "B.Paste")
			(net "PV_VCCP_NODE1")
		)
		(pad "2" smd rect
			(at 0.40005 0 270)
			(size 0.4572 0.508)
			(layers "B.Cu" "B.Mask" "B.Paste")
			(net "GND")
		)
	)
	(footprint ""
		(layer "B.Cu")
		(at 59.717178 -75.948286 90)
		(property "Reference" "C52"
			(at -31.091886 -14.285468 270)
			(unlocked yes)
			(layer "B.SilkS")
			(effects
				(font
					(size 0.7874 0.5842)
					(thickness 0.1524)
				)
				(justify left mirror)
			)
		)
		(property "Value" ""
			(at 0 0 90)
			(layer "B.Fab")
			(effects
				(font
					(size 1.27 1.27)
				)
				(justify mirror)
			)
		)
		(duplicate_pad_numbers_are_jumpers no)
		(fp_line
			(start 0.7874 -0.4064)
			(end -0.7874 -0.4064)
			(stroke
				(width 0.1524)
				(type default)
			)
			(layer "B.SilkS")
		)
		(fp_line
			(start -0.7874 -0.4064)
			(end -0.7874 0.4064)
			(stroke
				(width 0.1524)
				(type default)
			)
			(layer "B.SilkS")
		)
		(fp_line
			(start 0 0.381)
			(end 0 -0.381)
			(stroke
				(width 0.1524)
				(type default)
			)
			(layer "B.SilkS")
		)
		(fp_line
			(start 0.7874 0.4064)
			(end 0.7874 -0.4064)
			(stroke
				(width 0.1524)
				(type default)
			)
			(layer "B.SilkS")
		)
		(fp_line
			(start -0.7874 0.4064)
			(end 0.7874 0.4064)
			(stroke
				(width 0.1524)
				(type default)
			)
			(layer "B.SilkS")
		)
		(fp_poly
			(pts
				(xy 0.5334 0.254) (xy 0.635 0.254) (xy 0.635 0.2286) (xy 0.635 -0.254) (xy 0.5334 -0.254) (xy 0.5334 -0.2794)
				(xy -0.5334 -0.2794) (xy -0.5334 -0.254) (xy -0.635 -0.254) (xy -0.635 0.254) (xy -0.5334 0.254)
				(xy -0.5334 0.2794) (xy 0.508 0.2794) (xy 0.5334 0.2794)
			)
			(stroke
				(width 0)
				(type default)
			)
			(fill no)
			(layer "B.CrtYd")
		)
		(pad "1" smd rect
			(at -0.40005 0 270)
			(size 0.4572 0.508)
			(layers "B.Cu" "B.Mask" "B.Paste")
			(net "P1V05_NODE1")
		)
		(pad "2" smd rect
			(at 0.40005 0 270)
			(size 0.4572 0.508)
			(layers "B.Cu" "B.Mask" "B.Paste")
			(net "GND")
		)
	)
	(footprint ""
		(layer "B.Cu")
		(at 127.492252 -136.04367 90)
		(property "Reference" "C865"
			(at -5.140706 -0.20574 270)
			(unlocked yes)
			(layer "B.SilkS")
			(effects
				(font
					(size 0.7874 0.5842)
					(thickness 0.1524)
				)
				(justify left mirror)
			)
		)
		(property "Value" ""
			(at 0 0 90)
			(layer "B.Fab")
			(effects
				(font
					(size 1.27 1.27)
				)
				(justify mirror)
			)
		)
		(duplicate_pad_numbers_are_jumpers no)
		(fp_line
			(start 0.7874 -0.4064)
			(end -0.7874 -0.4064)
			(stroke
				(width 0.1524)
				(type default)
			)
			(layer "B.SilkS")
		)
		(fp_line
			(start -0.7874 -0.4064)
			(end -0.7874 0.4064)
			(stroke
				(width 0.1524)
				(type default)
			)
			(layer "B.SilkS")
		)
		(fp_line
			(start 0 0.381)
			(end 0 -0.381)
			(stroke
				(width 0.1524)
				(type default)
			)
			(layer "B.SilkS")
		)
		(fp_line
			(start 0.7874 0.4064)
			(end 0.7874 -0.4064)
			(stroke
				(width 0.1524)
				(type default)
			)
			(layer "B.SilkS")
		)
		(fp_line
			(start -0.7874 0.4064)
			(end 0.7874 0.4064)
			(stroke
				(width 0.1524)
				(type default)
			)
			(layer "B.SilkS")
		)
		(fp_poly
			(pts
				(xy 0.5334 0.254) (xy 0.635 0.254) (xy 0.635 0.2286) (xy 0.635 -0.254) (xy 0.5334 -0.254) (xy 0.5334 -0.2794)
				(xy -0.5334 -0.2794) (xy -0.5334 -0.254) (xy -0.635 -0.254) (xy -0.635 0.254) (xy -0.5334 0.254)
				(xy -0.5334 0.2794) (xy 0.508 0.2794) (xy 0.5334 0.2794)
			)
			(stroke
				(width 0)
				(type default)
			)
			(fill no)
			(layer "B.CrtYd")
		)
		(pad "1" smd rect
			(at -0.40005 0 270)
			(size 0.4572 0.508)
			(layers "B.Cu" "B.Mask" "B.Paste")
			(net "P3V3_NODE1")
		)
		(pad "2" smd rect
			(at 0.40005 0 270)
			(size 0.4572 0.508)
			(layers "B.Cu" "B.Mask" "B.Paste")
			(net "GND")
		)
	)
)
